# T6G (Grand Teton) — schematic netlist excerpt (pin names and nets, part order shuffled) for the footprints in the layout excerpt that follows; sources: Cadence DE-HDL packaged netlist, KiCad conversion of 04192023_DAF0TMB3IC0_F0TG_MB_C_brd_V02_OCP.brd

R6811  Q_RES  0 5% CHIP  pkg 0201LF  page 184 : A = SMB_RT_CPU1_P0_R_SCL ; B = SMB_RT_CPU1_P0_SCL
C275  Q_CAP  22UF 4V 20% X6S  pkg C0402  page 69 : A = PVDDCR_CPU0_P0 ; B = GND
R293  Q_RES  1K 1% CHIP  pkg 0402LF  page 88 : A = PWRGD_CHC_CPU0_DIMM ; B = PWRGD_CHAF_CPU0

(kicad_pcb
	(version 20260206)
	(generator "pcbnew")
	(generator_version "10.0")
	(general
		(thickness 1.6)
		(legacy_teardrops no)
	)
	(paper "A4")
	(title_block
		(title "04192023_DAF0TMB3IC0_F0TG_MB_C_brd_V02_OCP.brd")
		(comment 1 "Grand Teton / footprints 5365-5367 of 8354")
	)
	(layers
		(0 "F.Cu" signal "TOP")
		(4 "In1.Cu" signal "GND")
		(6 "In2.Cu" signal "IN1")
		(8 "In3.Cu" signal "GND1")
		(10 "In4.Cu" signal "IN2")
		(12 "In5.Cu" signal "GND2")
		(14 "In6.Cu" signal "IN3")
		(16 "In7.Cu" signal "GND3")
		(18 "In8.Cu" signal "VCC")
		(20 "In9.Cu" signal "VCC1")
		(22 "In10.Cu" signal "GND4")
		(24 "In11.Cu" signal "IN4")
		(26 "In12.Cu" signal "GND5")
		(28 "In13.Cu" signal "IN5")
		(30 "In14.Cu" signal "GND6")
		(32 "In15.Cu" signal "IN6")
		(34 "In16.Cu" signal "GND7")
		(2 "B.Cu" signal "BOTTOM")
		(9 "F.Adhes" user "F.Adhesive")
		(11 "B.Adhes" user "B.Adhesive")
		(13 "F.Paste" user "Package Geometry/Pastemask Top")
		(15 "B.Paste" user "Package Geometry/Pastemask Bottom")
		(5 "F.SilkS" user "Ref Des/Silkscreen Top")
		(7 "B.SilkS" user "Ref Des/Silkscreen Bottom")
		(1 "F.Mask" user "Board Geometry/Soldermask Top")
		(3 "B.Mask" user "Board Geometry/Soldermask Bottom")
		(17 "Dwgs.User" user "User.Drawings")
		(19 "Cmts.User" user "User.Comments")
		(21 "Eco1.User" user "User.Eco1")
		(23 "Eco2.User" user "User.Eco2")
		(25 "Edge.Cuts" user "Board Geometry/Outline")
		(27 "Margin" user)
		(31 "F.CrtYd" user "Package Geometry/Place Bound Top")
		(29 "B.CrtYd" user "Package Geometry/Place Bound Bottom")
		(35 "F.Fab" user "Ref Des/Assembly Top")
		(33 "B.Fab" user "Ref Des/Assembly Bottom")
	)
	(footprint ""
		(layer "B.Cu")
		(at 287.985454 -190.94831 180)
		(property "Reference" "R293"
			(at 0 0 0)
			(layer "B.SilkS")
			(hide yes)
			(effects
				(font
					(size 1.27 1.27)
				)
				(justify mirror)
			)
		)
		(property "Value" ""
			(at 0 0 0)
			(layer "B.Fab")
			(effects
				(font
					(size 1.27 1.27)
				)
				(justify mirror)
			)
		)
		(duplicate_pad_numbers_are_jumpers no)
		(fp_line
			(start 0.7874 0.4064)
			(end 0.7874 -0.4064)
			(stroke
				(width 0.1524)
				(type default)
			)
			(layer "B.SilkS")
		)
		(fp_line
			(start 0.7874 -0.4064)
			(end -0.7874 -0.4064)
			(stroke
				(width 0.1524)
				(type default)
			)
			(layer "B.SilkS")
		)
		(fp_line
			(start -0.7874 0.4064)
			(end 0.7874 0.4064)
			(stroke
				(width 0.1524)
				(type default)
			)
			(layer "B.SilkS")
		)
		(fp_line
			(start -0.7874 -0.4064)
			(end -0.7874 0.4064)
			(stroke
				(width 0.1524)
				(type default)
			)
			(layer "B.SilkS")
		)
		(fp_line
			(start 0.67945 0.3048)
			(end 0.67945 -0.305054)
			(stroke
				(width 0.1)
				(type default)
			)
			(layer "B.Fab")
		)
		(fp_line
			(start 0.67945 -0.305054)
			(end 0.12065 -0.305054)
			(stroke
				(width 0.1)
				(type default)
			)
			(layer "B.Fab")
		)
		(fp_line
			(start 0.12065 0.3048)
			(end 0.67945 0.3048)
			(stroke
				(width 0.1)
				(type default)
			)
			(layer "B.Fab")
		)
		(fp_line
			(start 0.12065 0.2794)
			(end 0.12065 0.3048)
			(stroke
				(width 0.1)
				(type default)
			)
			(layer "B.Fab")
		)
		(fp_line
			(start 0.12065 -0.2794)
			(end -0.12065 -0.2794)
			(stroke
				(width 0.1)
				(type default)
			)
			(layer "B.Fab")
		)
		(fp_line
			(start 0.12065 -0.305054)
			(end 0.12065 -0.2794)
			(stroke
				(width 0.1)
				(type default)
			)
			(layer "B.Fab")
		)
		(fp_line
			(start -0.120396 0.3048)
			(end -0.120396 0.2794)
			(stroke
				(width 0.1)
				(type default)
			)
			(layer "B.Fab")
		)
		(fp_line
			(start -0.120396 0.2794)
			(end 0.12065 0.2794)
			(stroke
				(width 0.1)
				(type default)
			)
			(layer "B.Fab")
		)
		(fp_line
			(start -0.12065 -0.2794)
			(end -0.12065 -0.3048)
			(stroke
				(width 0.1)
				(type default)
			)
			(layer "B.Fab")
		)
		(fp_line
			(start -0.12065 -0.3048)
			(end -0.67945 -0.3048)
			(stroke
				(width 0.1)
				(type default)
			)
			(layer "B.Fab")
		)
		(fp_line
			(start -0.67945 0.3048)
			(end -0.120396 0.3048)
			(stroke
				(width 0.1)
				(type default)
			)
			(layer "B.Fab")
		)
		(fp_line
			(start -0.67945 -0.3048)
			(end -0.67945 0.3048)
			(stroke
				(width 0.1)
				(type default)
			)
			(layer "B.Fab")
		)
		(pad "1" smd circle
			(at 0.40005 0)
			(size 0 0)
			(layers "B.Cu" "B.Mask" "B.Paste")
			(net "PWRGD_CHC_CPU0_DIMM")
		)
		(pad "2" smd circle
			(at -0.40005 0)
			(size 0 0)
			(layers "B.Cu" "B.Mask" "B.Paste")
			(net "PWRGD_CHAF_CPU0")
		)
	)
	(footprint ""
		(layer "B.Cu")
		(at 346.450158 -248.47931 180)
		(property "Reference" "C275"
			(at 0 0 0)
			(layer "B.SilkS")
			(hide yes)
			(effects
				(font
					(size 1.27 1.27)
				)
				(justify mirror)
			)
		)
		(property "Value" ""
			(at 0 0 0)
			(layer "B.Fab")
			(effects
				(font
					(size 1.27 1.27)
				)
				(justify mirror)
			)
		)
		(duplicate_pad_numbers_are_jumpers no)
		(fp_line
			(start 0.7874 0.4064)
			(end 0.7874 -0.4064)
			(stroke
				(width 0.1524)
				(type default)
			)
			(layer "B.SilkS")
		)
		(fp_line
			(start 0.7874 -0.4064)
			(end -0.7874 -0.4064)
			(stroke
				(width 0.1524)
				(type default)
			)
			(layer "B.SilkS")
		)
		(fp_line
			(start -0.7874 0.4064)
			(end 0.7874 0.4064)
			(stroke
				(width 0.1524)
				(type default)
			)
			(layer "B.SilkS")
		)
		(fp_line
			(start -0.7874 -0.4064)
			(end -0.7874 0.4064)
			(stroke
				(width 0.1524)
				(type default)
			)
			(layer "B.SilkS")
		)
		(fp_line
			(start 0.67945 0.3048)
			(end 0.67945 -0.305054)
			(stroke
				(width 0.1)
				(type default)
			)
			(layer "B.Fab")
		)
		(fp_line
			(start 0.67945 -0.305054)
			(end 0.12065 -0.305054)
			(stroke
				(width 0.1)
				(type default)
			)
			(layer "B.Fab")
		)
		(fp_line
			(start 0.12065 0.3048)
			(end 0.67945 0.3048)
			(stroke
				(width 0.1)
				(type default)
			)
			(layer "B.Fab")
		)
		(fp_line
			(start 0.12065 0.2794)
			(end 0.12065 0.3048)
			(stroke
				(width 0.1)
				(type default)
			)
			(layer "B.Fab")
		)
		(fp_line
			(start 0.12065 -0.2794)
			(end -0.12065 -0.2794)
			(stroke
				(width 0.1)
				(type default)
			)
			(layer "B.Fab")
		)
		(fp_line
			(start 0.12065 -0.305054)
			(end 0.12065 -0.2794)
			(stroke
				(width 0.1)
				(type default)
			)
			(layer "B.Fab")
		)
		(fp_line
			(start -0.120396 0.3048)
			(end -0.120396 0.2794)
			(stroke
				(width 0.1)
				(type default)
			)
			(layer "B.Fab")
		)
		(fp_line
			(start -0.120396 0.2794)
			(end 0.12065 0.2794)
			(stroke
				(width 0.1)
				(type default)
			)
			(layer "B.Fab")
		)
		(fp_line
			(start -0.12065 -0.2794)
			(end -0.12065 -0.3048)
			(stroke
				(width 0.1)
				(type default)
			)
			(layer "B.Fab")
		)
		(fp_line
			(start -0.12065 -0.3048)
			(end -0.67945 -0.3048)
			(stroke
				(width 0.1)
				(type default)
			)
			(layer "B.Fab")
		)
		(fp_line
			(start -0.67945 0.3048)
			(end -0.120396 0.3048)
			(stroke
				(width 0.1)
				(type default)
			)
			(layer "B.Fab")
		)
		(fp_line
			(start -0.67945 -0.3048)
			(end -0.67945 0.3048)
			(stroke
				(width 0.1)
				(type default)
			)
			(layer "B.Fab")
		)
		(pad "1" smd circle
			(at 0.40005 0)
			(size 0 0)
			(layers "B.Cu" "B.Mask" "B.Paste")
			(net "PVDDCR_CPU0_P0")
		)
		(pad "2" smd circle
			(at -0.40005 0)
			(size 0 0)
			(layers "B.Cu" "B.Mask" "B.Paste")
			(net "GND")
		)
	)
	(footprint ""
		(layer "B.Cu")
		(at 217.678 -335.026 180)
		(property "Reference" "R6811"
			(at 0 0 0)
			(layer "B.SilkS")
			(hide yes)
			(effects
				(font
					(size 1.27 1.27)
				)
				(justify mirror)
			)
		)
		(property "Value" ""
			(at 0 0 0)
			(layer "B.Fab")
			(effects
				(font
					(size 1.27 1.27)
				)
				(justify mirror)
			)
		)
		(duplicate_pad_numbers_are_jumpers no)
		(fp_line
			(start 0.32512 0.175006)
			(end 0.32512 -0.175006)
			(stroke
				(width 0.1)
				(type default)
			)
			(layer "B.Fab")
		)
		(fp_line
			(start 0.32512 -0.175006)
			(end -0.32512 -0.175006)
			(stroke
				(width 0.1)
				(type default)
			)
			(layer "B.Fab")
		)
		(fp_line
			(start -0.32512 0.175006)
			(end 0.32512 0.175006)
			(stroke
				(width 0.1)
				(type default)
			)
			(layer "B.Fab")
		)
		(fp_line
			(start -0.32512 -0.175006)
			(end -0.32512 0.175006)
			(stroke
				(width 0.1)
				(type default)
			)
			(layer "B.Fab")
		)
		(pad "1" smd rect
			(at 0.2667 0)
			(size 0.3048 0.381)
			(layers "B.Cu" "B.Mask" "B.Paste")
			(net "SMB_RT_CPU1_P0_R_SCL")
		)
		(pad "2" smd rect
			(at -0.2667 0 180)
			(size 0.3048 0.381)
			(layers "B.Cu" "B.Mask" "B.Paste")
			(net "SMB_RT_CPU1_P0_SCL")
		)
	)
)
